(kicad_pcb
	(version 20260206)
	(generator "pcbnew")
	(generator_version "10.0")
	(general
		(thickness 1.6)
		(legacy_teardrops no)
	)
	(paper "A4")
	(title_block
		(title "01162023_DA0F0TEBIF0_F0T_Expander_BD_F_brd_V02_OCP.brd")
		(comment 1 "Grand Teton / footprints 8169-8175 of 9728")
	)
	(layers
		(0 "F.Cu" signal "TOP")
		(4 "In1.Cu" signal "GND")
		(6 "In2.Cu" signal "VCC")
		(8 "In3.Cu" signal "VCC1")
		(10 "In4.Cu" signal "GND1")
		(12 "In5.Cu" signal "IN1")
		(14 "In6.Cu" signal "GND2")
		(16 "In7.Cu" signal "IN2")
		(18 "In8.Cu" signal "GND3")
		(20 "In9.Cu" signal "IN3")
		(22 "In10.Cu" signal "GND4")
		(24 "In11.Cu" signal "IN4")
		(26 "In12.Cu" signal "GND5")
		(28 "In13.Cu" signal "IN5")
		(30 "In14.Cu" signal "GND6")
		(32 "In15.Cu" signal "IN6")
		(34 "In16.Cu" signal "GND7")
		(2 "B.Cu" signal "BOTTOM")
		(9 "F.Adhes" user "F.Adhesive")
		(11 "B.Adhes" user "B.Adhesive")
		(13 "F.Paste" user "Package Geometry/Pastemask Top")
		(15 "B.Paste" user "Package Geometry/Pastemask Bottom")
		(5 "F.SilkS" user "Ref Des/Silkscreen Top")
		(7 "B.SilkS" user "Ref Des/Silkscreen Bottom")
		(1 "F.Mask" user "Board Geometry/Soldermask Top")
		(3 "B.Mask" user "Board Geometry/Soldermask Bottom")
		(17 "Dwgs.User" user "User.Drawings")
		(19 "Cmts.User" user "User.Comments")
		(21 "Eco1.User" user "User.Eco1")
		(23 "Eco2.User" user "User.Eco2")
		(25 "Edge.Cuts" user "Board Geometry/Outline")
		(27 "Margin" user)
		(31 "F.CrtYd" user "Package Geometry/Place Bound Top")
		(29 "B.CrtYd" user "Package Geometry/Place Bound Bottom")
		(35 "F.Fab" user "Ref Des/Assembly Top")
		(33 "B.Fab" user "Ref Des/Assembly Bottom")
	)
	(footprint ""
		(layer "B.Cu")
		(at 230.763318 -143.815054 -90)
		(property "Reference" "C2794"
			(at 0 0 90)
			(layer "B.SilkS")
			(hide yes)
			(effects
				(font
					(size 1.27 1.27)
				)
				(justify mirror)
			)
		)
		(property "Value" ""
			(at 0 0 90)
			(layer "B.Fab")
			(effects
				(font
					(size 1.27 1.27)
				)
				(justify mirror)
			)
		)
		(duplicate_pad_numbers_are_jumpers no)
		(fp_line
			(start -0.7874 0.4064)
			(end 0.7874 0.4064)
			(stroke
				(width 0.1524)
				(type default)
			)
			(layer "B.SilkS")
		)
		(fp_line
			(start 0.7874 0.4064)
			(end 0.7874 -0.4064)
			(stroke
				(width 0.1524)
				(type default)
			)
			(layer "B.SilkS")
		)
		(fp_line
			(start -0.7874 -0.4064)
			(end -0.7874 0.4064)
			(stroke
				(width 0.1524)
				(type default)
			)
			(layer "B.SilkS")
		)
		(fp_line
			(start 0.7874 -0.4064)
			(end -0.7874 -0.4064)
			(stroke
				(width 0.1524)
				(type default)
			)
			(layer "B.SilkS")
		)
		(fp_line
			(start -0.67945 0.3048)
			(end -0.120396 0.3048)
			(stroke
				(width 0.1)
				(type default)
			)
			(layer "B.Fab")
		)
		(fp_line
			(start -0.120396 0.3048)
			(end -0.120396 0.2794)
			(stroke
				(width 0.1)
				(type default)
			)
			(layer "B.Fab")
		)
		(fp_line
			(start 0.12065 0.3048)
			(end 0.67945 0.3048)
			(stroke
				(width 0.1)
				(type default)
			)
			(layer "B.Fab")
		)
		(fp_line
			(start 0.67945 0.3048)
			(end 0.67945 -0.305054)
			(stroke
				(width 0.1)
				(type default)
			)
			(layer "B.Fab")
		)
		(fp_line
			(start -0.120396 0.2794)
			(end 0.12065 0.2794)
			(stroke
				(width 0.1)
				(type default)
			)
			(layer "B.Fab")
		)
		(fp_line
			(start 0.12065 0.2794)
			(end 0.12065 0.3048)
			(stroke
				(width 0.1)
				(type default)
			)
			(layer "B.Fab")
		)
		(fp_line
			(start -0.12065 -0.2794)
			(end -0.12065 -0.3048)
			(stroke
				(width 0.1)
				(type default)
			)
			(layer "B.Fab")
		)
		(fp_line
			(start 0.12065 -0.2794)
			(end -0.12065 -0.2794)
			(stroke
				(width 0.1)
				(type default)
			)
			(layer "B.Fab")
		)
		(fp_line
			(start -0.67945 -0.3048)
			(end -0.67945 0.3048)
			(stroke
				(width 0.1)
				(type default)
			)
			(layer "B.Fab")
		)
		(fp_line
			(start -0.12065 -0.3048)
			(end -0.67945 -0.3048)
			(stroke
				(width 0.1)
				(type default)
			)
			(layer "B.Fab")
		)
		(fp_line
			(start 0.12065 -0.305054)
			(end 0.12065 -0.2794)
			(stroke
				(width 0.1)
				(type default)
			)
			(layer "B.Fab")
		)
		(fp_line
			(start 0.67945 -0.305054)
			(end 0.12065 -0.305054)
			(stroke
				(width 0.1)
				(type default)
			)
			(layer "B.Fab")
		)
		(pad "1" smd circle
			(at 0.40005 0 90)
			(size 0 0)
			(layers "B.Cu" "B.Mask" "B.Paste")
			(net "P3V3_CLK_GEN_VDDXTAL_CK440_PEX")
		)
		(pad "2" smd circle
			(at -0.40005 0 90)
			(size 0 0)
			(layers "B.Cu" "B.Mask" "B.Paste")
			(net "GND")
		)
	)
	(footprint ""
		(layer "B.Cu")
		(at 236.887512 -234.728004 90)
		(property "Reference" "R6197"
			(at 0 0 90)
			(layer "B.SilkS")
			(hide yes)
			(effects
				(font
					(size 1.27 1.27)
				)
				(justify mirror)
			)
		)
		(property "Value" ""
			(at 0 0 90)
			(layer "B.Fab")
			(effects
				(font
					(size 1.27 1.27)
				)
				(justify mirror)
			)
		)
		(duplicate_pad_numbers_are_jumpers no)
		(fp_line
			(start 0.7874 -0.4064)
			(end -0.7874 -0.4064)
			(stroke
				(width 0.1524)
				(type default)
			)
			(layer "B.SilkS")
		)
		(fp_line
			(start -0.7874 -0.4064)
			(end -0.7874 0.4064)
			(stroke
				(width 0.1524)
				(type default)
			)
			(layer "B.SilkS")
		)
		(fp_line
			(start 0.7874 0.4064)
			(end 0.7874 -0.4064)
			(stroke
				(width 0.1524)
				(type default)
			)
			(layer "B.SilkS")
		)
		(fp_line
			(start -0.7874 0.4064)
			(end 0.7874 0.4064)
			(stroke
				(width 0.1524)
				(type default)
			)
			(layer "B.SilkS")
		)
		(fp_line
			(start 0.67945 -0.305054)
			(end 0.12065 -0.305054)
			(stroke
				(width 0.1)
				(type default)
			)
			(layer "B.Fab")
		)
		(fp_line
			(start 0.12065 -0.305054)
			(end 0.12065 -0.2794)
			(stroke
				(width 0.1)
				(type default)
			)
			(layer "B.Fab")
		)
		(fp_line
			(start -0.12065 -0.3048)
			(end -0.67945 -0.3048)
			(stroke
				(width 0.1)
				(type default)
			)
			(layer "B.Fab")
		)
		(fp_line
			(start -0.67945 -0.3048)
			(end -0.67945 0.3048)
			(stroke
				(width 0.1)
				(type default)
			)
			(layer "B.Fab")
		)
		(fp_line
			(start 0.12065 -0.2794)
			(end -0.12065 -0.2794)
			(stroke
				(width 0.1)
				(type default)
			)
			(layer "B.Fab")
		)
		(fp_line
			(start -0.12065 -0.2794)
			(end -0.12065 -0.3048)
			(stroke
				(width 0.1)
				(type default)
			)
			(layer "B.Fab")
		)
		(fp_line
			(start 0.12065 0.2794)
			(end 0.12065 0.3048)
			(stroke
				(width 0.1)
				(type default)
			)
			(layer "B.Fab")
		)
		(fp_line
			(start -0.120396 0.2794)
			(end 0.12065 0.2794)
			(stroke
				(width 0.1)
				(type default)
			)
			(layer "B.Fab")
		)
		(fp_line
			(start 0.67945 0.3048)
			(end 0.67945 -0.305054)
			(stroke
				(width 0.1)
				(type default)
			)
			(layer "B.Fab")
		)
		(fp_line
			(start 0.12065 0.3048)
			(end 0.67945 0.3048)
			(stroke
				(width 0.1)
				(type default)
			)
			(layer "B.Fab")
		)
		(fp_line
			(start -0.120396 0.3048)
			(end -0.120396 0.2794)
			(stroke
				(width 0.1)
				(type default)
			)
			(layer "B.Fab")
		)
		(fp_line
			(start -0.67945 0.3048)
			(end -0.120396 0.3048)
			(stroke
				(width 0.1)
				(type default)
			)
			(layer "B.Fab")
		)
		(pad "1" smd circle
			(at 0.40005 0 270)
			(size 0 0)
			(layers "B.Cu" "B.Mask" "B.Paste")
			(net "GND")
		)
		(pad "2" smd circle
			(at -0.40005 0 270)
			(size 0 0)
			(layers "B.Cu" "B.Mask" "B.Paste")
			(net "SSD15_PWRDIS_BIC_R")
		)
	)
	(footprint ""
		(layer "B.Cu")
		(at 343.693242 -221.98711 90)
		(property "Reference" "C2033"
			(at 0 0 90)
			(layer "B.SilkS")
			(hide yes)
			(effects
				(font
					(size 1.27 1.27)
				)
				(justify mirror)
			)
		)
		(property "Value" ""
			(at 0 0 90)
			(layer "B.Fab")
			(effects
				(font
					(size 1.27 1.27)
				)
				(justify mirror)
			)
		)
		(duplicate_pad_numbers_are_jumpers no)
		(fp_line
			(start 0.69215 -0.2921)
			(end -0.69215 -0.2921)
			(stroke
				(width 0.1524)
				(type default)
			)
			(layer "B.SilkS")
		)
		(fp_line
			(start -0.69215 -0.2921)
			(end -0.69215 0.2921)
			(stroke
				(width 0.1524)
				(type default)
			)
			(layer "B.SilkS")
		)
		(fp_line
			(start 0.69215 0.2921)
			(end 0.69215 -0.2921)
			(stroke
				(width 0.1524)
				(type default)
			)
			(layer "B.SilkS")
		)
		(fp_line
			(start -0.69215 0.2921)
			(end 0.69215 0.2921)
			(stroke
				(width 0.1524)
				(type default)
			)
			(layer "B.SilkS")
		)
		(fp_line
			(start 0.51435 -0.2794)
			(end -0.51435 -0.2794)
			(stroke
				(width 0.1)
				(type default)
			)
			(layer "B.Fab")
		)
		(fp_line
			(start -0.51435 -0.2794)
			(end -0.51435 0.2794)
			(stroke
				(width 0.1)
				(type default)
			)
			(layer "B.Fab")
		)
		(fp_line
			(start 0.51435 0.2794)
			(end 0.51435 -0.2794)
			(stroke
				(width 0.1)
				(type default)
			)
			(layer "B.Fab")
		)
		(fp_line
			(start -0.51435 0.2794)
			(end 0.51435 0.2794)
			(stroke
				(width 0.1)
				(type default)
			)
			(layer "B.Fab")
		)
		(pad "1" smd circle
			(at 0.40005 0 270)
			(size 0 0)
			(layers "B.Cu" "B.Mask" "B.Paste")
			(net "P3V3_FPGA_VCCIO0")
		)
		(pad "2" smd circle
			(at -0.40005 0 270)
			(size 0 0)
			(layers "B.Cu" "B.Mask" "B.Paste")
			(net "GND")
		)
		(zone
			(layer "B.Cu")
			(hatch none 0.5)
			(connect_pads
				(clearance 0)
			)
			(min_thickness 0.25)
			(keepout
				(tracks not_allowed)
				(vias allowed)
				(pads allowed)
				(copperpour not_allowed)
				(footprints allowed)
			)
			(placement
				(enabled no)
				(sheetname "")
			)
			(fill
				(thermal_gap 0.5)
				(thermal_bridge_width 0.5)
				(island_removal_mode 0)
			)
			(polygon
				(pts
					(xy 343.780872 -222.17761) (xy 343.839038 -222.08617) (xy 343.839038 -221.88678) (xy 343.780872 -221.79661)
					(xy 343.605612 -221.79661) (xy 343.547192 -221.88678) (xy 343.547192 -222.08617) (xy 343.605358 -222.17761)
				)
			)
		)
	)
	(footprint ""
		(layer "B.Cu")
		(at 134.239 -282.040584 90)
		(property "Reference" "PR113"
			(at 0 0 90)
			(layer "B.SilkS")
			(hide yes)
			(effects
				(font
					(size 1.27 1.27)
				)
				(justify mirror)
			)
		)
		(property "Value" ""
			(at 0 0 90)
			(layer "B.Fab")
			(effects
				(font
					(size 1.27 1.27)
				)
				(justify mirror)
			)
		)
		(duplicate_pad_numbers_are_jumpers no)
		(fp_line
			(start 0.7874 -0.4064)
			(end -0.7874 -0.4064)
			(stroke
				(width 0.1524)
				(type default)
			)
			(layer "B.SilkS")
		)
		(fp_line
			(start -0.7874 -0.4064)
			(end -0.7874 0.4064)
			(stroke
				(width 0.1524)
				(type default)
			)
			(layer "B.SilkS")
		)
		(fp_line
			(start 0.7874 0.4064)
			(end 0.7874 -0.4064)
			(stroke
				(width 0.1524)
				(type default)
			)
			(layer "B.SilkS")
		)
		(fp_line
			(start -0.7874 0.4064)
			(end 0.7874 0.4064)
			(stroke
				(width 0.1524)
				(type default)
			)
			(layer "B.SilkS")
		)
		(fp_line
			(start 0.67945 -0.305054)
			(end 0.12065 -0.305054)
			(stroke
				(width 0.1)
				(type default)
			)
			(layer "B.Fab")
		)
		(fp_line
			(start 0.12065 -0.305054)
			(end 0.12065 -0.2794)
			(stroke
				(width 0.1)
				(type default)
			)
			(layer "B.Fab")
		)
		(fp_line
			(start -0.12065 -0.3048)
			(end -0.67945 -0.3048)
			(stroke
				(width 0.1)
				(type default)
			)
			(layer "B.Fab")
		)
		(fp_line
			(start -0.67945 -0.3048)
			(end -0.67945 0.3048)
			(stroke
				(width 0.1)
				(type default)
			)
			(layer "B.Fab")
		)
		(fp_line
			(start 0.12065 -0.2794)
			(end -0.12065 -0.2794)
			(stroke
				(width 0.1)
				(type default)
			)
			(layer "B.Fab")
		)
		(fp_line
			(start -0.12065 -0.2794)
			(end -0.12065 -0.3048)
			(stroke
				(width 0.1)
				(type default)
			)
			(layer "B.Fab")
		)
		(fp_line
			(start 0.12065 0.2794)
			(end 0.12065 0.3048)
			(stroke
				(width 0.1)
				(type default)
			)
			(layer "B.Fab")
		)
		(fp_line
			(start -0.120396 0.2794)
			(end 0.12065 0.2794)
			(stroke
				(width 0.1)
				(type default)
			)
			(layer "B.Fab")
		)
		(fp_line
			(start 0.67945 0.3048)
			(end 0.67945 -0.305054)
			(stroke
				(width 0.1)
				(type default)
			)
			(layer "B.Fab")
		)
		(fp_line
			(start 0.12065 0.3048)
			(end 0.67945 0.3048)
			(stroke
				(width 0.1)
				(type default)
			)
			(layer "B.Fab")
		)
		(fp_line
			(start -0.120396 0.3048)
			(end -0.120396 0.2794)
			(stroke
				(width 0.1)
				(type default)
			)
			(layer "B.Fab")
		)
		(fp_line
			(start -0.67945 0.3048)
			(end -0.120396 0.3048)
			(stroke
				(width 0.1)
				(type default)
			)
			(layer "B.Fab")
		)
		(pad "1" smd circle
			(at 0.40005 0 270)
			(size 0 0)
			(layers "B.Cu" "B.Mask" "B.Paste")
			(net "SW_P0V8_PEX1_VOS2")
		)
		(pad "2" smd circle
			(at -0.40005 0 270)
			(size 0 0)
			(layers "B.Cu" "B.Mask" "B.Paste")
			(net "P0V8_PEX1")
		)
	)
	(footprint ""
		(layer "B.Cu")
		(at 243.3193 -207.982566 180)
		(property "Reference" "C2020"
			(at 0 0 0)
			(layer "B.SilkS")
			(hide yes)
			(effects
				(font
					(size 1.27 1.27)
				)
				(justify mirror)
			)
		)
		(property "Value" ""
			(at 0 0 0)
			(layer "B.Fab")
			(effects
				(font
					(size 1.27 1.27)
				)
				(justify mirror)
			)
		)
		(duplicate_pad_numbers_are_jumpers no)
		(fp_line
			(start 1.2954 0.5842)
			(end 1.2954 -0.5842)
			(stroke
				(width 0.1524)
				(type default)
			)
			(layer "B.SilkS")
		)
		(fp_line
			(start 1.2954 -0.5842)
			(end -1.2954 -0.5842)
			(stroke
				(width 0.1524)
				(type default)
			)
			(layer "B.SilkS")
		)
		(fp_line
			(start -1.2954 0.5842)
			(end 1.2954 0.5842)
			(stroke
				(width 0.1524)
				(type default)
			)
			(layer "B.SilkS")
		)
		(fp_line
			(start -1.2954 -0.5842)
			(end -1.2954 0.5842)
			(stroke
				(width 0.1524)
				(type default)
			)
			(layer "B.SilkS")
		)
		(fp_line
			(start 1.1938 0.4064)
			(end 1.1938 -0.4064)
			(stroke
				(width 0.1)
				(type default)
			)
			(layer "B.Fab")
		)
		(fp_line
			(start 1.1938 -0.4064)
			(end 0.8636 -0.4064)
			(stroke
				(width 0.1)
				(type default)
			)
			(layer "B.Fab")
		)
		(fp_line
			(start 0.8636 0.4572)
			(end 0.8636 0.4064)
			(stroke
				(width 0.1)
				(type default)
			)
			(layer "B.Fab")
		)
		(fp_line
			(start 0.8636 0.4064)
			(end 1.1938 0.4064)
			(stroke
				(width 0.1)
				(type default)
			)
			(layer "B.Fab")
		)
		(fp_line
			(start 0.8636 -0.4064)
			(end 0.8636 -0.4572)
			(stroke
				(width 0.1)
				(type default)
			)
			(layer "B.Fab")
		)
		(fp_line
			(start 0.8636 -0.4572)
			(end -0.8636 -0.4572)
			(stroke
				(width 0.1)
				(type default)
			)
			(layer "B.Fab")
		)
		(fp_line
			(start -0.8636 0.4572)
			(end 0.8636 0.4572)
			(stroke
				(width 0.1)
				(type default)
			)
			(layer "B.Fab")
		)
		(fp_line
			(start -0.8636 0.4064)
			(end -0.8636 0.4572)
			(stroke
				(width 0.1)
				(type default)
			)
			(layer "B.Fab")
		)
		(fp_line
			(start -0.8636 -0.4064)
			(end -1.1938 -0.4064)
			(stroke
				(width 0.1)
				(type default)
			)
			(layer "B.Fab")
		)
		(fp_line
			(start -0.8636 -0.4572)
			(end -0.8636 -0.4064)
			(stroke
				(width 0.1)
				(type default)
			)
			(layer "B.Fab")
		)
		(fp_line
			(start -1.1938 0.4064)
			(end -0.8636 0.4064)
			(stroke
				(width 0.1)
				(type default)
			)
			(layer "B.Fab")
		)
		(fp_line
			(start -1.1938 -0.4064)
			(end -1.1938 0.4064)
			(stroke
				(width 0.1)
				(type default)
			)
			(layer "B.Fab")
		)
		(pad "1" smd rect
			(at 0.7366 0 90)
			(size 0.7112 0.8128)
			(layers "B.Cu" "B.Mask" "B.Paste")
			(net "P1V2_AUX")
		)
		(pad "2" smd rect
			(at -0.7366 0 90)
			(size 0.7112 0.8128)
			(layers "B.Cu" "B.Mask" "B.Paste")
			(net "GND")
		)
	)
	(footprint ""
		(layer "B.Cu")
		(at 236.015784 -91.472766)
		(property "Reference" "C2617"
			(at 0 0 0)
			(layer "B.SilkS")
			(hide yes)
			(effects
				(font
					(size 1.27 1.27)
				)
				(justify mirror)
			)
		)
		(property "Value" ""
			(at 0 0 0)
			(layer "B.Fab")
			(effects
				(font
					(size 1.27 1.27)
				)
				(justify mirror)
			)
		)
		(duplicate_pad_numbers_are_jumpers no)
		(fp_line
			(start -0.7874 -0.4064)
			(end -0.7874 0.4064)
			(stroke
				(width 0.1524)
				(type default)
			)
			(layer "B.SilkS")
		)
		(fp_line
			(start -0.7874 0.4064)
			(end 0.7874 0.4064)
			(stroke
				(width 0.1524)
				(type default)
			)
			(layer "B.SilkS")
		)
		(fp_line
			(start 0.7874 -0.4064)
			(end -0.7874 -0.4064)
			(stroke
				(width 0.1524)
				(type default)
			)
			(layer "B.SilkS")
		)
		(fp_line
			(start 0.7874 0.4064)
			(end 0.7874 -0.4064)
			(stroke
				(width 0.1524)
				(type default)
			)
			(layer "B.SilkS")
		)
		(fp_line
			(start -0.67945 -0.3048)
			(end -0.67945 0.3048)
			(stroke
				(width 0.1)
				(type default)
			)
			(layer "B.Fab")
		)
		(fp_line
			(start -0.67945 0.3048)
			(end -0.120396 0.3048)
			(stroke
				(width 0.1)
				(type default)
			)
			(layer "B.Fab")
		)
		(fp_line
			(start -0.12065 -0.3048)
			(end -0.67945 -0.3048)
			(stroke
				(width 0.1)
				(type default)
			)
			(layer "B.Fab")
		)
		(fp_line
			(start -0.12065 -0.2794)
			(end -0.12065 -0.3048)
			(stroke
				(width 0.1)
				(type default)
			)
			(layer "B.Fab")
		)
		(fp_line
			(start -0.120396 0.2794)
			(end 0.12065 0.2794)
			(stroke
				(width 0.1)
				(type default)
			)
			(layer "B.Fab")
		)
		(fp_line
			(start -0.120396 0.3048)
			(end -0.120396 0.2794)
			(stroke
				(width 0.1)
				(type default)
			)
			(layer "B.Fab")
		)
		(fp_line
			(start 0.12065 -0.305054)
			(end 0.12065 -0.2794)
			(stroke
				(width 0.1)
				(type default)
			)
			(layer "B.Fab")
		)
		(fp_line
			(start 0.12065 -0.2794)
			(end -0.12065 -0.2794)
			(stroke
				(width 0.1)
				(type default)
			)
			(layer "B.Fab")
		)
		(fp_line
			(start 0.12065 0.2794)
			(end 0.12065 0.3048)
			(stroke
				(width 0.1)
				(type default)
			)
			(layer "B.Fab")
		)
		(fp_line
			(start 0.12065 0.3048)
			(end 0.67945 0.3048)
			(stroke
				(width 0.1)
				(type default)
			)
			(layer "B.Fab")
		)
		(fp_line
			(start 0.67945 -0.305054)
			(end 0.12065 -0.305054)
			(stroke
				(width 0.1)
				(type default)
			)
			(layer "B.Fab")
		)
		(fp_line
			(start 0.67945 0.3048)
			(end 0.67945 -0.305054)
			(stroke
				(width 0.1)
				(type default)
			)
			(layer "B.Fab")
		)
		(pad "1" smd circle
			(at 0.40005 0 180)
			(size 0 0)
			(layers "B.Cu" "B.Mask" "B.Paste")
			(net "P3V3_PEX_USB_HUB")
		)
		(pad "2" smd circle
			(at -0.40005 0 180)
			(size 0 0)
			(layers "B.Cu" "B.Mask" "B.Paste")
			(net "GND")
		)
	)
	(footprint ""
		(layer "B.Cu")
		(at 57.220104 -305.399948 -90)
		(property "Reference" "C2974"
			(at 0 0 90)
			(layer "B.SilkS")
			(hide yes)
			(effects
				(font
					(size 1.27 1.27)
				)
				(justify mirror)
			)
		)
		(property "Value" ""
			(at 0 0 90)
			(layer "B.Fab")
			(effects
				(font
					(size 1.27 1.27)
				)
				(justify mirror)
			)
		)
		(duplicate_pad_numbers_are_jumpers no)
		(fp_line
			(start -0.299974 0.150114)
			(end 0.299974 0.150114)
			(stroke
				(width 0.1)
				(type default)
			)
			(layer "B.Fab")
		)
		(fp_line
			(start 0.299974 0.150114)
			(end 0.299974 -0.150114)
			(stroke
				(width 0.1)
				(type default)
			)
			(layer "B.Fab")
		)
		(fp_line
			(start -0.299974 -0.150114)
			(end -0.299974 0.150114)
			(stroke
				(width 0.1)
				(type default)
			)
			(layer "B.Fab")
		)
		(fp_line
			(start 0.299974 -0.150114)
			(end -0.299974 -0.150114)
			(stroke
				(width 0.1)
				(type default)
			)
			(layer "B.Fab")
		)
		(pad "1" smd rect
			(at 0.2667 0 90)
			(size 0.3048 0.381)
			(layers "B.Cu" "B.Mask" "B.Paste")
			(net "P1V25_SERDES_VDDPLL_PEX0")
		)
		(pad "2" smd rect
			(at -0.2667 0 90)
			(size 0.3048 0.381)
			(layers "B.Cu" "B.Mask" "B.Paste")
			(net "GND")
		)
	)
)
